(kicad_pcb
	(version 20221018)
	(generator pcbnew)
	(general
    (thickness 1.518)
  )
	(paper "A4")
	(title_block
    (title "Kria K26 Devboard")
    (date "2024-03-26")
    (rev "1.2.5")
    (comment 1 "www.antmicro.com")
    (comment 2 "Antmicro Ltd.")
		(comment 9 "footprints 56-59 of 660")
	)
	(layers
    (0 "F.Cu" mixed)
    (1 "In1.Cu" power)
    (2 "In2.Cu" mixed)
    (3 "In3.Cu" power)
    (4 "In4.Cu" mixed)
    (5 "In5.Cu" power)
    (6 "In6.Cu" mixed)
    (31 "B.Cu" power)
    (32 "B.Adhes" user "B.Adhesive")
    (33 "F.Adhes" user "F.Adhesive")
    (34 "B.Paste" user)
    (35 "F.Paste" user)
    (36 "B.SilkS" user "B.Silkscreen")
    (37 "F.SilkS" user "F.Silkscreen")
    (38 "B.Mask" user)
    (39 "F.Mask" user)
    (40 "Dwgs.User" user "User.Drawings")
    (41 "Cmts.User" user "User.Comments")
    (42 "Eco1.User" user "User.Eco1")
    (43 "Eco2.User" user "User.Eco2")
    (44 "Edge.Cuts" user)
    (45 "Margin" user)
    (46 "B.CrtYd" user "B.Courtyard")
    (47 "F.CrtYd" user "F.Courtyard")
    (48 "B.Fab" user)
    (49 "F.Fab" user)
  )
	(footprint "kria-k26-devboard-footprints:L_0806_2016Metric" (layer "F.Cu")
    (at 178.39 136.01)
    (property "Author" "Antmicro")
    (property "IMax" "")
    (property "ISat" "")
    (property "License" "Apache-2.0")
    (property "MPN" "SRP2010-1R0M")
    (property "Manufacturer" "Bourns")
    (property "Sheetfile" "dc-dc-conventers.kicad_sch")
    (property "Sheetname" "DC/DC conventers")
    (property "Size" "2.0x1.6")
    (property "Val" "1u/2.6A")
    (attr smd)
    (fp_text reference "L8" (at 0.63 -4.78 180) (layer "F.SilkS")
        (effects (font (size 0.7 0.7) (thickness 0.15)) (justify left bottom))
    )
    (fp_text value "L_1u_2.6A_0806" (at 0 2) (layer "F.Fab") hide
        (effects (font (size 0.7 0.7) (thickness 0.15)) (justify left bottom))
    )
    (fp_text user "Author: Antmicro" (at -1.9 4.4) (layer "F.Fab") hide
        (effects (font (size 0.7 0.7) (thickness 0.15)) (justify left bottom))
    )
    (fp_text user "${REFERENCE}" (at -1.9 3.1) (layer "F.Fab") hide
        (effects (font (size 0.7 0.7) (thickness 0.15)) (justify left bottom))
    )
    (fp_text user "License: Apache-2.0" (at -1.9 5.75) (layer "F.Fab") hide
        (effects (font (size 0.7 0.7) (thickness 0.15)) (justify left bottom))
    )
    (fp_line (start -0.301 0.9) (end 0.299 0.9)
      (stroke (width 0.15) (type solid)) (layer "F.SilkS"))
    (fp_line (start -0.3 -0.9) (end 0.298 -0.9)
      (stroke (width 0.15) (type solid)) (layer "F.SilkS"))
    (fp_rect (start -1.75 -1.05) (end 1.75 1.05)
      (stroke (width 0.05) (type solid)) (fill none) (layer "F.CrtYd"))
    (fp_rect (start -0.951 -0.882) (end 0.949 0.875)
      (stroke (width 0.15) (type solid)) (fill none) (layer "F.Fab"))
    (pad "1" smd roundrect (at -1.1 -0.001) (size 1 1.8) (layers "F.Cu" "F.Paste" "F.Mask") (roundrect_rratio 0.15)
      (net 315 "/Power Supply/DC/DC conventers/SW_PL_3V3") (pintype "passive"))
    (pad "2" smd roundrect (at 1.1 -0.001) (size 1 1.8) (layers "F.Cu" "F.Paste" "F.Mask") (roundrect_rratio 0.15)
      (net 770 "/Power Supply/DC/DC conventers/PL_3V3_OUT") (pintype "passive"))
  )
	(footprint "kria-k26-devboard-footprints:PinHeader_2x7_P2mm_Drill1mm_Shrouded" (layer "F.Cu")
    (at 76.8 130.975 90)
    (property "Author" "Antmicro")
    (property "License" "Apache-2.0")
    (property "MPN" "0878311420")
    (property "Manufacturer" "Molex")
    (property "Sheetfile" "debug.kicad_sch")
    (property "Sheetname" "Debug and JTAG")
    (property "ki_description" "Pin Header, Wire-to-Board, 2 mm, 2 Rows, 14 Contacts, Surface Mount Straight, Milli-Grid 87832")
    (property "ki_keywords" "PINSTRIP, HEADER ")
    (attr through_hole)
    (fp_text reference "J9" (at -14.525 5.26 90) (layer "F.SilkS")
        (effects (font (size 0.7 0.7) (thickness 0.15)) (justify left bottom))
    )
    (fp_text value "PinHeader_2x7_P2mm_Drill1mm_Shrouded" (at -14.7 5.4 90) (layer "F.Fab") hide
        (effects (font (size 0.7 0.7) (thickness 0.15)) (justify left bottom))
    )
    (fp_text user "License: Apache-2.0" (at -14.7 7.9 90) (layer "F.Fab")
        (effects (font (size 0.7 0.7) (thickness 0.15)) (justify left bottom))
    )
    (fp_text user "${REFERENCE}" (at -14.7 6.7 90) (layer "F.Fab")
        (effects (font (size 0.7 0.7) (thickness 0.15)) (justify left bottom))
    )
    (fp_text user "Author: Antmicro" (at -14.7 9.2 90) (layer "F.Fab")
        (effects (font (size 0.7 0.7) (thickness 0.15)) (justify left bottom))
    )
    (fp_line (start -14.41 -2.24) (end -14.41 -1.74)
      (stroke (width 0.15) (type solid)) (layer "F.SilkS"))
    (fp_line (start -14.41 -2.24) (end -13.91 -2.24)
      (stroke (width 0.15) (type solid)) (layer "F.SilkS"))
    (fp_line (start -14.41 4.24) (end -14.41 3.74)
      (stroke (width 0.15) (type solid)) (layer "F.SilkS"))
    (fp_line (start -14.41 4.24) (end -13.91 4.24)
      (stroke (width 0.15) (type solid)) (layer "F.SilkS"))
    (fp_line (start 2.41 -2.24) (end 1.91 -2.24)
      (stroke (width 0.15) (type solid)) (layer "F.SilkS"))
    (fp_line (start 2.41 -2.24) (end 2.41 -1.74)
      (stroke (width 0.15) (type solid)) (layer "F.SilkS"))
    (fp_line (start 2.41 4.24) (end 1.91 4.24)
      (stroke (width 0.15) (type solid)) (layer "F.SilkS"))
    (fp_line (start 2.41 4.24) (end 2.41 3.74)
      (stroke (width 0.15) (type solid)) (layer "F.SilkS"))
    (fp_line (start -14.51 -2.34) (end -14.51 4.34)
      (stroke (width 0.05) (type solid)) (layer "F.CrtYd"))
    (fp_line (start 2.51 -2.34) (end -14.51 -2.34)
      (stroke (width 0.05) (type solid)) (layer "F.CrtYd"))
    (fp_line (start 2.51 -2.34) (end 2.51 4.34)
      (stroke (width 0.05) (type solid)) (layer "F.CrtYd"))
    (fp_line (start 2.51 4.34) (end -14.51 4.34)
      (stroke (width 0.05) (type solid)) (layer "F.CrtYd"))
    (fp_line (start -14.356 -2.15) (end 2.293 -2.15)
      (stroke (width 0.15) (type solid)) (layer "F.Fab"))
    (fp_line (start -14.356 -1.898) (end -14.356 4.15)
      (stroke (width 0.15) (type solid)) (layer "F.Fab"))
    (fp_line (start -14.356 4.15) (end 2.32 4.15)
      (stroke (width 0.15) (type solid)) (layer "F.Fab"))
    (fp_line (start 2.33 -2.15) (end 2.33 4.13)
      (stroke (width 0.15) (type solid)) (layer "F.Fab"))
    (pad "1" thru_hole rect (at 0 0 90) (size 1.75 1.75) (drill 1) (layers "*.Cu" "*.Mask")
      (net 1 "GND") (pintype "passive"))
    (pad "2" thru_hole circle (at 0 1.999 90) (size 1.75 1.75) (drill 1) (layers "*.Cu" "*.Mask")
      (net 17 "PS_1V8") (pintype "passive"))
    (pad "3" thru_hole circle (at -2 0 90) (size 1.75 1.75) (drill 1) (layers "*.Cu" "*.Mask")
      (net 1 "GND") (pintype "passive"))
    (pad "4" thru_hole circle (at -2 1.999 90) (size 1.75 1.75) (drill 1) (layers "*.Cu" "*.Mask")
      (net 145 "/Debug and JTAG/JTAG_TMS_C2M") (pintype "passive"))
    (pad "5" thru_hole circle (at -4 0 90) (size 1.75 1.75) (drill 1) (layers "*.Cu" "*.Mask")
      (net 1 "GND") (pintype "passive"))
    (pad "6" thru_hole circle (at -4 1.999 90) (size 1.75 1.75) (drill 1) (layers "*.Cu" "*.Mask")
      (net 143 "/Debug and JTAG/JTAG_TCK_C2M") (pintype "passive"))
    (pad "7" thru_hole circle (at -6 0 90) (size 1.75 1.75) (drill 1) (layers "*.Cu" "*.Mask")
      (net 1 "GND") (pintype "passive"))
    (pad "8" thru_hole circle (at -6 1.999 90) (size 1.75 1.75) (drill 1) (layers "*.Cu" "*.Mask")
      (net 142 "/Debug and JTAG/JTAG_TDO_M2C") (pintype "passive"))
    (pad "9" thru_hole circle (at -8 0 90) (size 1.75 1.75) (drill 1) (layers "*.Cu" "*.Mask")
      (net 1 "GND") (pintype "passive"))
    (pad "10" thru_hole circle (at -8 1.999 90) (size 1.75 1.75) (drill 1) (layers "*.Cu" "*.Mask")
      (net 141 "/Debug and JTAG/JTAG_TDI_C2M") (pintype "passive"))
    (pad "11" thru_hole circle (at -10 0 90) (size 1.75 1.75) (drill 1) (layers "*.Cu" "*.Mask")
      (net 1 "GND") (pintype "passive"))
    (pad "12" thru_hole circle (at -10 1.999 90) (size 1.75 1.75) (drill 1) (layers "*.Cu" "*.Mask")
      (net 434 "unconnected-(J9-Pad12)") (pintype "passive+no_connect"))
    (pad "13" thru_hole circle (at -12 0 90) (size 1.75 1.75) (drill 1) (layers "*.Cu" "*.Mask")
      (net 140 "/Debug and JTAG/~{PS_SRST_C2M}") (pintype "passive"))
    (pad "14" thru_hole circle (at -12 1.999 90) (size 1.75 1.75) (drill 1) (layers "*.Cu" "*.Mask")
      (net 220 "/Debug and JTAG/CONN_GND") (pintype "passive"))
  )
	(footprint "kria-k26-devboard-footprints:DFN-14-1EP_4x3mm_P0.5mm" (layer "F.Cu")
    (at 186.6 122.1 90)
    (property "Author" "Antmicro")
    (property "License" "Apache-2.0")
    (property "MPN" "LTC4358CDE#PBF")
    (property "Manufacturer" "Analog Devices")
    (property "Sheetfile" "supply-oring.kicad_sch")
    (property "Sheetname" "Supply ORing")
    (property "ki_description" "Ideal diode")
    (property "ki_keywords" "SMT, PMIC, IC, POWER, MANAGEMENT, DIODE, CONTROLLER")
    (attr smd)
    (fp_text reference "U56" (at 0.02 2.97 90) (layer "F.SilkS")
        (effects (font (size 0.7 0.7) (thickness 0.15)) (justify left bottom))
    )
    (fp_text value "LTC4358CDE" (at 0 3.2 90) (layer "F.Fab") hide
        (effects (font (size 0.7 0.7) (thickness 0.15)) (justify left bottom))
    )
    (fp_text user "${REFERENCE}" (at -0.659 5.797 90) (layer "F.Fab") hide
        (effects (font (size 0.7 0.7) (thickness 0.15)) (justify left bottom))
    )
    (fp_text user "Author: Antmicro" (at -0.659 6.998 90) (layer "F.Fab") hide
        (effects (font (size 0.7 0.7) (thickness 0.15)) (justify left bottom))
    )
    (fp_text user "License: Apache-2.0" (at -0.659 8.198 90) (layer "F.Fab") hide
        (effects (font (size 0.7 0.7) (thickness 0.15)) (justify left bottom))
    )
    (fp_line (start -1.6 -2.045) (end 1.5995 -2.045)
      (stroke (width 0.15) (type solid)) (layer "F.SilkS"))
    (fp_line (start -1.6 2.044) (end 1.6 2.044)
      (stroke (width 0.15) (type solid)) (layer "F.SilkS"))
    (fp_circle (center -1.85 -1.9) (end -1.8 -1.9)
      (stroke (width 0.15) (type solid)) (fill solid) (layer "F.SilkS"))
    (fp_line (start -2.1 -1.87) (end -1.79 -1.87)
      (stroke (width 0.05) (type solid)) (layer "F.CrtYd"))
    (fp_line (start -2.1 1.9) (end -2.1 -1.87)
      (stroke (width 0.05) (type solid)) (layer "F.CrtYd"))
    (fp_line (start -1.79 -2.28) (end 1.81 -2.28)
      (stroke (width 0.05) (type solid)) (layer "F.CrtYd"))
    (fp_line (start -1.79 -1.87) (end -1.79 -2.28)
      (stroke (width 0.05) (type solid)) (layer "F.CrtYd"))
    (fp_line (start -1.79 1.9) (end -2.1 1.9)
      (stroke (width 0.05) (type solid)) (layer "F.CrtYd"))
    (fp_line (start -1.79 2.31) (end -1.79 1.9)
      (stroke (width 0.05) (type solid)) (layer "F.CrtYd"))
    (fp_line (start 1.81 -2.28) (end 1.81 -1.87)
      (stroke (width 0.05) (type solid)) (layer "F.CrtYd"))
    (fp_line (start 1.81 1.9) (end 1.81 2.31)
      (stroke (width 0.05) (type solid)) (layer "F.CrtYd"))
    (fp_line (start 1.81 2.31) (end -1.79 2.31)
      (stroke (width 0.05) (type solid)) (layer "F.CrtYd"))
    (fp_line (start 2.1 -1.87) (end 1.81 -1.87)
      (stroke (width 0.05) (type solid)) (layer "F.CrtYd"))
    (fp_line (start 2.1 -1.87) (end 2.1 1.9)
      (stroke (width 0.05) (type solid)) (layer "F.CrtYd"))
    (fp_line (start 2.1 1.9) (end 1.81 1.9)
      (stroke (width 0.05) (type solid)) (layer "F.CrtYd"))
    (fp_line (start -1.55 -2.045) (end -1.55 2.044)
      (stroke (width 0.15) (type solid)) (layer "F.Fab"))
    (fp_line (start -1.55 2.044) (end 1.549 2.044)
      (stroke (width 0.15) (type solid)) (layer "F.Fab"))
    (fp_line (start 1.549 -2.045) (end -1.55 -2.045)
      (stroke (width 0.15) (type solid)) (layer "F.Fab"))
    (fp_line (start 1.549 2.044) (end 1.549 -2.045)
      (stroke (width 0.15) (type solid)) (layer "F.Fab"))
    (pad "" smd roundrect (at 0 -0.8 90) (size 1.3 1.3) (layers "F.Paste") (roundrect_rratio 0.05))
    (pad "" smd roundrect (at 0 0.8 90) (size 1.3 1.3) (layers "F.Paste") (roundrect_rratio 0.05))
    (pad "1" smd roundrect (at -1.445 -1.499 90) (size 0.807999 0.2548) (layers "F.Cu" "F.Paste" "F.Mask") (roundrect_rratio 0.25)
      (net 13 "/Power Supply/PoE/POE_12V") (pinfunction "IN") (pintype "input"))
    (pad "2" smd roundrect (at -1.445 -1.001 90) (size 0.807999 0.2548) (layers "F.Cu" "F.Paste" "F.Mask") (roundrect_rratio 0.25)
      (net 13 "/Power Supply/PoE/POE_12V") (pinfunction "IN") (pintype "passive"))
    (pad "3" smd roundrect (at -1.445 -0.5 90) (size 0.807999 0.2548) (layers "F.Cu" "F.Paste" "F.Mask") (roundrect_rratio 0.25)
      (net 13 "/Power Supply/PoE/POE_12V") (pinfunction "IN") (pintype "passive"))
    (pad "4" smd roundrect (at -1.445 0 90) (size 0.807999 0.2548) (layers "F.Cu" "F.Paste" "F.Mask") (roundrect_rratio 0.25)
      (net 13 "/Power Supply/PoE/POE_12V") (pinfunction "IN") (pintype "passive"))
    (pad "5" smd roundrect (at -1.445 0.5 90) (size 0.807999 0.2548) (layers "F.Cu" "F.Paste" "F.Mask") (roundrect_rratio 0.25)
      (net 785 "unconnected-(U56-GATE-Pad5)") (pinfunction "GATE") (pintype "output+no_connect"))
    (pad "6" smd roundrect (at -1.445 1 90) (size 0.807999 0.2548) (layers "F.Cu" "F.Paste" "F.Mask") (roundrect_rratio 0.25)
      (net 786 "unconnected-(U56-NC-Pad6)") (pinfunction "NC") (pintype "no_connect"))
    (pad "7" smd roundrect (at -1.445 1.5 90) (size 0.807999 0.2548) (layers "F.Cu" "F.Paste" "F.Mask") (roundrect_rratio 0.25)
      (net 1 "GND") (pinfunction "GND") (pintype "power_in"))
    (pad "8" smd roundrect (at 1.445 1.5 90) (size 0.807999 0.2548) (layers "F.Cu" "F.Paste" "F.Mask") (roundrect_rratio 0.25)
      (net 14 "/Power Supply/DC/DC conventers/DC_MAIN_BUS") (pinfunction "VDD") (pintype "passive"))
    (pad "9" smd roundrect (at 1.445 1 90) (size 0.807999 0.2548) (layers "F.Cu" "F.Paste" "F.Mask") (roundrect_rratio 0.25)
      (net 14 "/Power Supply/DC/DC conventers/DC_MAIN_BUS") (pinfunction "OUT") (pintype "passive"))
    (pad "10" smd roundrect (at 1.445 0.5 90) (size 0.807999 0.2548) (layers "F.Cu" "F.Paste" "F.Mask") (roundrect_rratio 0.25)
      (net 787 "unconnected-(U56-NC-Pad10)") (pinfunction "NC") (pintype "no_connect"))
    (pad "11" smd roundrect (at 1.445 0 90) (size 0.807999 0.2548) (layers "F.Cu" "F.Paste" "F.Mask") (roundrect_rratio 0.25)
      (net 13 "/Power Supply/PoE/POE_12V") (pinfunction "IN") (pintype "passive"))
    (pad "12" smd roundrect (at 1.445 -0.501 90) (size 0.807999 0.2548) (layers "F.Cu" "F.Paste" "F.Mask") (roundrect_rratio 0.25)
      (net 13 "/Power Supply/PoE/POE_12V") (pinfunction "IN") (pintype "passive"))
    (pad "13" smd roundrect (at 1.445 -1.001 90) (size 0.807999 0.2548) (layers "F.Cu" "F.Paste" "F.Mask") (roundrect_rratio 0.25)
      (net 13 "/Power Supply/PoE/POE_12V") (pinfunction "IN") (pintype "passive"))
    (pad "14" smd roundrect (at 1.445 -1.499 90) (size 0.807999 0.2548) (layers "F.Cu" "F.Paste" "F.Mask") (roundrect_rratio 0.25)
      (net 13 "/Power Supply/PoE/POE_12V") (pinfunction "IN") (pintype "passive"))
    (pad "15" smd roundrect (at 0 0 90) (size 1.8034 3.4036) (layers "F.Cu" "F.Mask") (roundrect_rratio 0.05)
      (net 14 "/Power Supply/DC/DC conventers/DC_MAIN_BUS") (pinfunction "DRAIN") (pintype "passive"))
  )
	(footprint "kria-k26-devboard-footprints:R_0402_1005Metric" (layer "F.Cu")
    (at 188.475 137.575 180)
    (descr "Resistor SMD 0402")
    (tags "resistor SMD 0402")
    (property "Author" "Antmicro")
    (property "License" "Apache-2.0")
    (property "MPN" "CR0402-FX-1001GLF")
    (property "Manufacturer" "Bourns")
    (property "Sheetfile" "dc-dc-conventers.kicad_sch")
    (property "Sheetname" "DC/DC conventers")
    (property "Tolerance" "1%")
    (property "Val" "1k")
    (property "ki_description" "1k resistor in 0402 package with 1% tolerance")
    (attr smd)
    (fp_text reference "R143" (at -0.185 -3.315 270) (layer "F.SilkS")
        (effects (font (size 0.7 0.7) (thickness 0.15)) (justify left bottom))
    )
    (fp_text value "R_1k_0402" (at 0 1.4 180) (layer "F.Fab") hide
        (effects (font (size 0.7 0.7) (thickness 0.15)) (justify left bottom))
    )
    (fp_text user "License: Apache-2.0" (at -0.95 5.169 180) (layer "F.Fab") hide
        (effects (font (size 0.7 0.7) (thickness 0.15)) (justify left bottom))
    )
    (fp_text user "${REFERENCE}" (at -0.95 3.168 180) (layer "F.Fab") hide
        (effects (font (size 0.7 0.7) (thickness 0.15)) (justify left bottom))
    )
    (fp_text user "Author: Antmicro" (at -0.95 4.169 180) (layer "F.Fab") hide
        (effects (font (size 0.7 0.7) (thickness 0.15)) (justify left bottom))
    )
    (fp_rect (start -0.93 -0.47) (end 0.93 0.47)
      (stroke (width 0.05) (type solid)) (fill none) (layer "F.CrtYd"))
    (fp_rect (start -0.5 -0.25) (end 0.5 0.25)
      (stroke (width 0.15) (type solid)) (fill none) (layer "F.Fab"))
    (pad "1" smd roundrect (at -0.485 0 180) (size 0.59 0.64) (layers "F.Cu" "F.Paste" "F.Mask") (roundrect_rratio 0.25)
      (net 770 "/Power Supply/DC/DC conventers/PL_3V3_OUT") (pintype "passive"))
    (pad "2" smd roundrect (at 0.485 0 180) (size 0.59 0.64) (layers "F.Cu" "F.Paste" "F.Mask") (roundrect_rratio 0.25)
      (net 192 "Net-(D20-Pad1)") (pintype "passive"))
  )
)
